(kicad_pcb
	(version 20260206)
	(generator "pcbnew")
	(generator_version "10.0")
	(general
		(thickness 1.6)
		(legacy_teardrops no)
	)
	(paper "A4")
	(title_block
		(title "Bryce Canyon_IOM_IOC_16318-2_OCP.brd")
		(comment 1 "Bryce Canyon / footprints 1012-1019 of 1605")
	)
	(layers
		(0 "F.Cu" signal "TOP")
		(4 "In1.Cu" signal "L2GND")
		(6 "In2.Cu" signal "L3")
		(8 "In3.Cu" signal "L4VCC")
		(10 "In4.Cu" signal "L5VCC")
		(12 "In5.Cu" signal "L6")
		(14 "In6.Cu" signal "L7GND")
		(2 "B.Cu" signal "BOTTOM")
		(9 "F.Adhes" user "F.Adhesive")
		(11 "B.Adhes" user "B.Adhesive")
		(13 "F.Paste" user "Package Geometry/Pastemask Top")
		(15 "B.Paste" user "Package Geometry/Pastemask Bottom")
		(5 "F.SilkS" user "Ref Des/Silkscreen Top")
		(7 "B.SilkS" user "Ref Des/Silkscreen Bottom")
		(1 "F.Mask" user "Board Geometry/Soldermask Top")
		(3 "B.Mask" user "Board Geometry/Soldermask Bottom")
		(17 "Dwgs.User" user "User.Drawings")
		(19 "Cmts.User" user "User.Comments")
		(21 "Eco1.User" user "User.Eco1")
		(23 "Eco2.User" user "User.Eco2")
		(25 "Edge.Cuts" user "Board Geometry/Outline")
		(27 "Margin" user)
		(31 "F.CrtYd" user "Package Geometry/Place Bound Top")
		(29 "B.CrtYd" user "Package Geometry/Place Bound Bottom")
		(35 "F.Fab" user "Ref Des/Assembly Top")
		(33 "B.Fab" user "Ref Des/Assembly Bottom")
	)
	(footprint ""
		(layer "B.Cu")
		(at 10.193528 -132.402834 90)
		(property "Reference" "R237"
			(at 0 0 90)
			(layer "B.SilkS")
			(hide yes)
			(effects
				(font
					(size 1.27 1.27)
				)
				(justify mirror)
			)
		)
		(property "Value" "120R2F-GP"
			(at -0.064008 -3.993896 90)
			(unlocked yes)
			(layer "B.Fab")
			(hide yes)
			(effects
				(font
					(size 1.016 1.016)
					(thickness 0.1524)
				)
				(justify mirror)
			)
		)
		(property "Device Type" "R402H16"
			(at -0.064008 -5.517896 90)
			(unlocked yes)
			(layer "B.Fab")
			(hide yes)
			(effects
				(font
					(size 1.016 1.016)
					(thickness 0.1524)
				)
				(justify mirror)
			)
		)
		(duplicate_pad_numbers_are_jumpers no)
		(fp_line
			(start 0.508 -0.9398)
			(end 0.508 0.9398)
			(stroke
				(width 0.1524)
				(type default)
			)
			(layer "B.SilkS")
		)
		(fp_line
			(start -0.508 -0.9398)
			(end 0.508 -0.9398)
			(stroke
				(width 0.1524)
				(type default)
			)
			(layer "B.SilkS")
		)
		(fp_rect
			(start 0.508 0.9398)
			(end -0.508 -0.9398)
			(stroke
				(width 0)
				(type default)
			)
			(fill no)
			(layer "B.CrtYd")
		)
		(fp_rect
			(start 0.508 0.9398)
			(end -0.508 -0.9398)
			(stroke
				(width 0)
				(type default)
			)
			(fill no)
			(layer "B.Fab")
		)
		(pad "1" smd custom
			(at 0 -0.4445 270)
			(size 0.1397 0.1397)
			(layers "B.Cu" "B.Mask" "B.Paste")
			(net "GND")
			(options
				(clearance outline)
				(anchor circle)
			)
			(primitives
				(gr_poly
					(pts
						(arc
							(start -0.1778 0.2794)
							(mid -0.249642 0.249642)
							(end -0.2794 0.1778)
						)
						(arc
							(start -0.2794 -0.1778)
							(mid -0.249642 -0.249642)
							(end -0.1778 -0.2794)
						)
						(arc
							(start 0.1778 -0.2794)
							(mid 0.249642 -0.249642)
							(end 0.2794 -0.1778)
						)
						(arc
							(start 0.2794 0.1778)
							(mid 0.249642 0.249642)
							(end 0.1778 0.2794)
						)
					)
					(width 0)
					(fill yes)
				)
			)
		)
		(pad "2" smd custom
			(at 0 0.4445 270)
			(size 0.1397 0.1397)
			(layers "B.Cu" "B.Mask" "B.Paste")
			(net "MEMA_2")
			(options
				(clearance outline)
				(anchor circle)
			)
			(primitives
				(gr_poly
					(pts
						(arc
							(start -0.1778 0.2794)
							(mid -0.249642 0.249642)
							(end -0.2794 0.1778)
						)
						(arc
							(start -0.2794 -0.1778)
							(mid -0.249642 -0.249642)
							(end -0.1778 -0.2794)
						)
						(arc
							(start 0.1778 -0.2794)
							(mid 0.249642 -0.249642)
							(end 0.2794 -0.1778)
						)
						(arc
							(start 0.2794 0.1778)
							(mid 0.249642 0.249642)
							(end 0.1778 0.2794)
						)
					)
					(width 0)
					(fill yes)
				)
			)
		)
	)
	(footprint ""
		(layer "B.Cu")
		(at 52.0446 -165.8874 90)
		(property "Reference" "R414"
			(at 0 0 90)
			(layer "B.SilkS")
			(hide yes)
			(effects
				(font
					(size 1.27 1.27)
				)
				(justify mirror)
			)
		)
		(property "Value" "1KR2F-3-GP"
			(at -0.064008 -3.993896 90)
			(unlocked yes)
			(layer "B.Fab")
			(hide yes)
			(effects
				(font
					(size 1.016 1.016)
					(thickness 0.1524)
				)
				(justify mirror)
			)
		)
		(property "Device Type" "R402H16"
			(at -0.064008 -5.517896 90)
			(unlocked yes)
			(layer "B.Fab")
			(hide yes)
			(effects
				(font
					(size 1.016 1.016)
					(thickness 0.1524)
				)
				(justify mirror)
			)
		)
		(duplicate_pad_numbers_are_jumpers no)
		(fp_line
			(start 0.508 -0.9398)
			(end 0.508 0.9398)
			(stroke
				(width 0.1524)
				(type default)
			)
			(layer "B.SilkS")
		)
		(fp_line
			(start -0.508 -0.9398)
			(end 0.508 -0.9398)
			(stroke
				(width 0.1524)
				(type default)
			)
			(layer "B.SilkS")
		)
		(fp_rect
			(start 0.508 0.9398)
			(end -0.508 -0.9398)
			(stroke
				(width 0)
				(type default)
			)
			(fill no)
			(layer "B.CrtYd")
		)
		(fp_rect
			(start 0.508 0.9398)
			(end -0.508 -0.9398)
			(stroke
				(width 0)
				(type default)
			)
			(fill no)
			(layer "B.Fab")
		)
		(pad "1" smd custom
			(at 0 -0.4445 270)
			(size 0.1397 0.1397)
			(layers "B.Cu" "B.Mask" "B.Paste")
			(net "P0V975")
			(options
				(clearance outline)
				(anchor circle)
			)
			(primitives
				(gr_poly
					(pts
						(arc
							(start -0.1778 0.2794)
							(mid -0.249642 0.249642)
							(end -0.2794 0.1778)
						)
						(arc
							(start -0.2794 -0.1778)
							(mid -0.249642 -0.249642)
							(end -0.1778 -0.2794)
						)
						(arc
							(start 0.1778 -0.2794)
							(mid 0.249642 -0.249642)
							(end 0.2794 -0.1778)
						)
						(arc
							(start 0.2794 0.1778)
							(mid 0.249642 0.249642)
							(end 0.1778 0.2794)
						)
					)
					(width 0)
					(fill yes)
				)
			)
		)
		(pad "2" smd custom
			(at 0 0.4445 270)
			(size 0.1397 0.1397)
			(layers "B.Cu" "B.Mask" "B.Paste")
			(net "ADC_P0V975")
			(options
				(clearance outline)
				(anchor circle)
			)
			(primitives
				(gr_poly
					(pts
						(arc
							(start -0.1778 0.2794)
							(mid -0.249642 0.249642)
							(end -0.2794 0.1778)
						)
						(arc
							(start -0.2794 -0.1778)
							(mid -0.249642 -0.249642)
							(end -0.1778 -0.2794)
						)
						(arc
							(start 0.1778 -0.2794)
							(mid 0.249642 -0.249642)
							(end 0.2794 -0.1778)
						)
						(arc
							(start 0.2794 0.1778)
							(mid 0.249642 0.249642)
							(end 0.1778 0.2794)
						)
					)
					(width 0)
					(fill yes)
				)
			)
		)
	)
	(footprint ""
		(layer "B.Cu")
		(at 191.689736 -25.908 -90)
		(property "Reference" "C490"
			(at 0 0 90)
			(layer "B.SilkS")
			(hide yes)
			(effects
				(font
					(size 1.27 1.27)
				)
				(justify mirror)
			)
		)
		(property "Value" "SCD01U16V1KX-GP"
			(at 2.8321 -1.7399 270)
			(unlocked yes)
			(layer "B.Fab")
			(hide yes)
			(effects
				(font
					(size 1.016 1.016)
					(thickness 0.1524)
				)
				(justify mirror)
			)
		)
		(property "Device Type" "C0201H13"
			(at 2.8321 -3.2639 270)
			(unlocked yes)
			(layer "B.Fab")
			(hide yes)
			(effects
				(font
					(size 1.016 1.016)
					(thickness 0.1524)
				)
				(justify mirror)
			)
		)
		(duplicate_pad_numbers_are_jumpers no)
		(fp_rect
			(start 0.2794 0.6477)
			(end -0.2794 -0.6477)
			(stroke
				(width 0)
				(type default)
			)
			(fill no)
			(layer "B.CrtYd")
		)
		(fp_rect
			(start 0.2794 0.6477)
			(end -0.2794 -0.6477)
			(stroke
				(width 0)
				(type default)
			)
			(fill no)
			(layer "B.Fab")
		)
		(pad "1" smd custom
			(at 0 -0.2794 90)
			(size 0.0762 0.0762)
			(layers "B.Cu" "B.Mask" "B.Paste")
			(net "PHY_CON_A_TO_IOC_3_DP")
			(options
				(clearance outline)
				(anchor circle)
			)
			(primitives
				(gr_poly
					(pts
						(arc
							(start 0.1524 0.127)
							(mid 0.137521 0.162921)
							(end 0.1016 0.1778)
						)
						(arc
							(start -0.1016 0.1778)
							(mid -0.137521 0.162921)
							(end -0.1524 0.127)
						)
						(arc
							(start -0.1524 -0.127)
							(mid -0.137521 -0.162921)
							(end -0.1016 -0.1778)
						)
						(arc
							(start 0.1016 -0.1778)
							(mid 0.137521 -0.162921)
							(end 0.1524 -0.127)
						)
					)
					(width 0)
					(fill yes)
				)
			)
		)
		(pad "2" smd custom
			(at 0 0.2794 90)
			(size 0.0762 0.0762)
			(layers "B.Cu" "B.Mask" "B.Paste")
			(net "PHY_CON_A_TO_IOC_3_DP_C")
			(options
				(clearance outline)
				(anchor circle)
			)
			(primitives
				(gr_poly
					(pts
						(arc
							(start 0.1524 0.127)
							(mid 0.137521 0.162921)
							(end 0.1016 0.1778)
						)
						(arc
							(start -0.1016 0.1778)
							(mid -0.137521 0.162921)
							(end -0.1524 0.127)
						)
						(arc
							(start -0.1524 -0.127)
							(mid -0.137521 -0.162921)
							(end -0.1016 -0.1778)
						)
						(arc
							(start 0.1016 -0.1778)
							(mid 0.137521 -0.162921)
							(end 0.1524 -0.127)
						)
					)
					(width 0)
					(fill yes)
				)
			)
		)
	)
	(footprint ""
		(layer "B.Cu")
		(at 187.7314 -76.740004)
		(property "Reference" "TP89"
			(at 0 0 0)
			(layer "B.SilkS")
			(hide yes)
			(effects
				(font
					(size 1.27 1.27)
				)
				(justify mirror)
			)
		)
		(property "Value" "TPAD28-2-GP"
			(at 0.0127 -1.6637 0)
			(unlocked yes)
			(layer "B.Fab")
			(hide yes)
			(effects
				(font
					(size 1.016 1.016)
					(thickness 0.1524)
				)
				(justify mirror)
			)
		)
		(property "Device Type" "TPAD28"
			(at 0.0127 -3.1877 0)
			(unlocked yes)
			(layer "B.Fab")
			(hide yes)
			(effects
				(font
					(size 1.016 1.016)
					(thickness 0.1524)
				)
				(justify mirror)
			)
		)
		(duplicate_pad_numbers_are_jumpers no)
		(fp_poly
			(pts
				(arc
					(start 0.3556 0)
					(mid -0.3556 0)
					(end 0.3556 0)
				)
			)
			(stroke
				(width 0)
				(type default)
			)
			(fill no)
			(layer "B.CrtYd")
		)
		(fp_poly
			(pts
				(arc
					(start 0.6096 0)
					(mid -0.6096 0)
					(end 0.6096 0)
				)
			)
			(stroke
				(width 0)
				(type default)
			)
			(fill no)
			(layer "B.Fab")
		)
		(pad "1" smd circle
			(at 0 0 180)
			(size 0.7112 0.7112)
			(layers "B.Cu" "B.Mask" "B.Paste")
			(net "IOC_GPIO_3")
		)
	)
	(footprint ""
		(layer "B.Cu")
		(at 57.3278 -145.2626 -90)
		(property "Reference" "R361"
			(at 0 0 90)
			(layer "B.SilkS")
			(hide yes)
			(effects
				(font
					(size 1.27 1.27)
				)
				(justify mirror)
			)
		)
		(property "Value" "10KR2F-2-GP"
			(at -0.064008 -3.993896 270)
			(unlocked yes)
			(layer "B.Fab")
			(hide yes)
			(effects
				(font
					(size 1.016 1.016)
					(thickness 0.1524)
				)
				(justify mirror)
			)
		)
		(property "Device Type" "R402H16"
			(at -0.064008 -5.517896 270)
			(unlocked yes)
			(layer "B.Fab")
			(hide yes)
			(effects
				(font
					(size 1.016 1.016)
					(thickness 0.1524)
				)
				(justify mirror)
			)
		)
		(duplicate_pad_numbers_are_jumpers no)
		(fp_line
			(start -0.508 -0.9398)
			(end 0.508 -0.9398)
			(stroke
				(width 0.1524)
				(type default)
			)
			(layer "B.SilkS")
		)
		(fp_line
			(start 0.508 -0.9398)
			(end 0.508 0.9398)
			(stroke
				(width 0.1524)
				(type default)
			)
			(layer "B.SilkS")
		)
		(fp_rect
			(start 0.508 0.9398)
			(end -0.508 -0.9398)
			(stroke
				(width 0)
				(type default)
			)
			(fill no)
			(layer "B.CrtYd")
		)
		(fp_rect
			(start 0.508 0.9398)
			(end -0.508 -0.9398)
			(stroke
				(width 0)
				(type default)
			)
			(fill no)
			(layer "B.Fab")
		)
		(pad "1" smd custom
			(at 0 -0.4445 90)
			(size 0.1397 0.1397)
			(layers "B.Cu" "B.Mask" "B.Paste")
			(net "P3V3_STBY")
			(options
				(clearance outline)
				(anchor circle)
			)
			(primitives
				(gr_poly
					(pts
						(arc
							(start -0.1778 0.2794)
							(mid -0.249642 0.249642)
							(end -0.2794 0.1778)
						)
						(arc
							(start -0.2794 -0.1778)
							(mid -0.249642 -0.249642)
							(end -0.1778 -0.2794)
						)
						(arc
							(start 0.1778 -0.2794)
							(mid 0.249642 -0.249642)
							(end 0.2794 -0.1778)
						)
						(arc
							(start 0.2794 0.1778)
							(mid 0.249642 0.249642)
							(end 0.1778 0.2794)
						)
					)
					(width 0)
					(fill yes)
				)
			)
		)
		(pad "2" smd custom
			(at 0 0.4445 90)
			(size 0.1397 0.1397)
			(layers "B.Cu" "B.Mask" "B.Paste")
			(net "JTAG_BMC_TDO")
			(options
				(clearance outline)
				(anchor circle)
			)
			(primitives
				(gr_poly
					(pts
						(arc
							(start -0.1778 0.2794)
							(mid -0.249642 0.249642)
							(end -0.2794 0.1778)
						)
						(arc
							(start -0.2794 -0.1778)
							(mid -0.249642 -0.249642)
							(end -0.1778 -0.2794)
						)
						(arc
							(start 0.1778 -0.2794)
							(mid 0.249642 -0.249642)
							(end 0.2794 -0.1778)
						)
						(arc
							(start 0.2794 0.1778)
							(mid 0.249642 0.249642)
							(end 0.1778 0.2794)
						)
					)
					(width 0)
					(fill yes)
				)
			)
		)
	)
	(footprint ""
		(layer "B.Cu")
		(at 48.999394 -161.276792)
		(property "Reference" "R310"
			(at 0 0 0)
			(layer "B.SilkS")
			(hide yes)
			(effects
				(font
					(size 1.27 1.27)
				)
				(justify mirror)
			)
		)
		(property "Value" "4K7R2F-GP"
			(at -0.064008 -3.993896 0)
			(unlocked yes)
			(layer "B.Fab")
			(hide yes)
			(effects
				(font
					(size 1.016 1.016)
					(thickness 0.1524)
				)
				(justify mirror)
			)
		)
		(property "Device Type" "R402H16"
			(at -0.064008 -5.517896 0)
			(unlocked yes)
			(layer "B.Fab")
			(hide yes)
			(effects
				(font
					(size 1.016 1.016)
					(thickness 0.1524)
				)
				(justify mirror)
			)
		)
		(duplicate_pad_numbers_are_jumpers no)
		(fp_line
			(start -0.508 -0.9398)
			(end 0.508 -0.9398)
			(stroke
				(width 0.1524)
				(type default)
			)
			(layer "B.SilkS")
		)
		(fp_line
			(start 0.508 -0.9398)
			(end 0.508 0.9398)
			(stroke
				(width 0.1524)
				(type default)
			)
			(layer "B.SilkS")
		)
		(fp_rect
			(start 0.508 0.9398)
			(end -0.508 -0.9398)
			(stroke
				(width 0)
				(type default)
			)
			(fill no)
			(layer "B.CrtYd")
		)
		(fp_rect
			(start 0.508 0.9398)
			(end -0.508 -0.9398)
			(stroke
				(width 0)
				(type default)
			)
			(fill no)
			(layer "B.Fab")
		)
		(pad "1" smd custom
			(at 0 -0.4445 180)
			(size 0.1397 0.1397)
			(layers "B.Cu" "B.Mask" "B.Paste")
			(net "P3V3_STBY")
			(options
				(clearance outline)
				(anchor circle)
			)
			(primitives
				(gr_poly
					(pts
						(arc
							(start -0.1778 0.2794)
							(mid -0.249642 0.249642)
							(end -0.2794 0.1778)
						)
						(arc
							(start -0.2794 -0.1778)
							(mid -0.249642 -0.249642)
							(end -0.1778 -0.2794)
						)
						(arc
							(start 0.1778 -0.2794)
							(mid 0.249642 -0.249642)
							(end 0.2794 -0.1778)
						)
						(arc
							(start 0.2794 0.1778)
							(mid 0.249642 0.249642)
							(end 0.1778 0.2794)
						)
					)
					(width 0)
					(fill yes)
				)
			)
		)
		(pad "2" smd custom
			(at 0 0.4445 180)
			(size 0.1397 0.1397)
			(layers "B.Cu" "B.Mask" "B.Paste")
			(net "BOARD_REV_1")
			(options
				(clearance outline)
				(anchor circle)
			)
			(primitives
				(gr_poly
					(pts
						(arc
							(start -0.1778 0.2794)
							(mid -0.249642 0.249642)
							(end -0.2794 0.1778)
						)
						(arc
							(start -0.2794 -0.1778)
							(mid -0.249642 -0.249642)
							(end -0.1778 -0.2794)
						)
						(arc
							(start 0.1778 -0.2794)
							(mid 0.249642 -0.249642)
							(end 0.2794 -0.1778)
						)
						(arc
							(start 0.2794 0.1778)
							(mid 0.249642 0.249642)
							(end 0.1778 0.2794)
						)
					)
					(width 0)
					(fill yes)
				)
			)
		)
	)
	(footprint ""
		(layer "B.Cu")
		(at 177.78095 -80.948276)
		(property "Reference" "C362"
			(at 0 0 0)
			(layer "B.SilkS")
			(hide yes)
			(effects
				(font
					(size 1.27 1.27)
				)
				(justify mirror)
			)
		)
		(property "Value" "SC100U6D3V6MX-GP"
			(at 0.0762 -5.1308 0)
			(unlocked yes)
			(layer "B.Fab")
			(hide yes)
			(effects
				(font
					(size 1.016 1.016)
					(thickness 0.1524)
				)
				(justify mirror)
			)
		)
		(property "Device Type" "C1206H71"
			(at 0.127 -6.6548 0)
			(unlocked yes)
			(layer "B.Fab")
			(hide yes)
			(effects
				(font
					(size 1.016 1.016)
					(thickness 0.1524)
				)
				(justify mirror)
			)
		)
		(duplicate_pad_numbers_are_jumpers no)
		(fp_line
			(start -1.016 -2.2352)
			(end -1.016 -0.8382)
			(stroke
				(width 0.1524)
				(type default)
			)
			(layer "B.SilkS")
		)
		(fp_line
			(start -1.016 0.8382)
			(end -1.016 2.2352)
			(stroke
				(width 0.1524)
				(type default)
			)
			(layer "B.SilkS")
		)
		(fp_line
			(start -1.016 2.2352)
			(end 1.016 2.2352)
			(stroke
				(width 0.1524)
				(type default)
			)
			(layer "B.SilkS")
		)
		(fp_line
			(start 1.016 -2.2352)
			(end -1.016 -2.2352)
			(stroke
				(width 0.1524)
				(type default)
			)
			(layer "B.SilkS")
		)
		(fp_line
			(start 1.016 -0.8382)
			(end 1.016 -2.2352)
			(stroke
				(width 0.1524)
				(type default)
			)
			(layer "B.SilkS")
		)
		(fp_line
			(start 1.016 2.2352)
			(end 1.016 0.8382)
			(stroke
				(width 0.1524)
				(type default)
			)
			(layer "B.SilkS")
		)
		(fp_rect
			(start 1.0922 2.3114)
			(end -1.0922 -2.3114)
			(stroke
				(width 0)
				(type default)
			)
			(fill no)
			(layer "B.CrtYd")
		)
		(fp_poly
			(pts
				(xy -1.0922 -2.3114) (xy -1.0922 2.3114) (xy 1.0922 2.3114) (xy 1.0922 -2.3114)
			)
			(stroke
				(width 0)
				(type default)
			)
			(fill no)
			(layer "B.Fab")
		)
		(pad "1" smd rect
			(at 0 -1.397 180)
			(size 1.651 1.27)
			(layers "B.Cu" "B.Mask" "B.Paste")
			(net "GND")
		)
		(pad "2" smd rect
			(at 0 1.397 180)
			(size 1.651 1.27)
			(layers "B.Cu" "B.Mask" "B.Paste")
			(net "PCE_AVDD")
		)
	)
	(footprint ""
		(layer "B.Cu")
		(at 95.377 -7.874 90)
		(property "Reference" "R37"
			(at 0 0 90)
			(layer "B.SilkS")
			(hide yes)
			(effects
				(font
					(size 1.27 1.27)
				)
				(justify mirror)
			)
		)
		(property "Value" "1MR2F-GP"
			(at -0.064008 -3.993896 90)
			(unlocked yes)
			(layer "B.Fab")
			(hide yes)
			(effects
				(font
					(size 1.016 1.016)
					(thickness 0.1524)
				)
				(justify mirror)
			)
		)
		(property "Device Type" "R402H16"
			(at -0.064008 -5.517896 90)
			(unlocked yes)
			(layer "B.Fab")
			(hide yes)
			(effects
				(font
					(size 1.016 1.016)
					(thickness 0.1524)
				)
				(justify mirror)
			)
		)
		(duplicate_pad_numbers_are_jumpers no)
		(fp_line
			(start 0.508 -0.9398)
			(end 0.508 0.9398)
			(stroke
				(width 0.1524)
				(type default)
			)
			(layer "B.SilkS")
		)
		(fp_line
			(start -0.508 -0.9398)
			(end 0.508 -0.9398)
			(stroke
				(width 0.1524)
				(type default)
			)
			(layer "B.SilkS")
		)
		(fp_rect
			(start 0.508 0.9398)
			(end -0.508 -0.9398)
			(stroke
				(width 0)
				(type default)
			)
			(fill no)
			(layer "B.CrtYd")
		)
		(fp_rect
			(start 0.508 0.9398)
			(end -0.508 -0.9398)
			(stroke
				(width 0)
				(type default)
			)
			(fill no)
			(layer "B.Fab")
		)
		(pad "1" smd custom
			(at 0 -0.4445 270)
			(size 0.1397 0.1397)
			(layers "B.Cu" "B.Mask" "B.Paste")
			(net "USB_CONN_GND")
			(options
				(clearance outline)
				(anchor circle)
			)
			(primitives
				(gr_poly
					(pts
						(arc
							(start -0.1778 0.2794)
							(mid -0.249642 0.249642)
							(end -0.2794 0.1778)
						)
						(arc
							(start -0.2794 -0.1778)
							(mid -0.249642 -0.249642)
							(end -0.1778 -0.2794)
						)
						(arc
							(start 0.1778 -0.2794)
							(mid 0.249642 -0.249642)
							(end 0.2794 -0.1778)
						)
						(arc
							(start 0.2794 0.1778)
							(mid 0.249642 0.249642)
							(end 0.1778 0.2794)
						)
					)
					(width 0)
					(fill yes)
				)
			)
		)
		(pad "2" smd custom
			(at 0 0.4445 270)
			(size 0.1397 0.1397)
			(layers "B.Cu" "B.Mask" "B.Paste")
			(net "GND")
			(options
				(clearance outline)
				(anchor circle)
			)
			(primitives
				(gr_poly
					(pts
						(arc
							(start -0.1778 0.2794)
							(mid -0.249642 0.249642)
							(end -0.2794 0.1778)
						)
						(arc
							(start -0.2794 -0.1778)
							(mid -0.249642 -0.249642)
							(end -0.1778 -0.2794)
						)
						(arc
							(start 0.1778 -0.2794)
							(mid 0.249642 -0.249642)
							(end 0.2794 -0.1778)
						)
						(arc
							(start 0.2794 0.1778)
							(mid 0.249642 0.249642)
							(end 0.1778 0.2794)
						)
					)
					(width 0)
					(fill yes)
				)
			)
		)
	)
)
